(kicad_pcb
	(version 20260206)
	(generator "pcbnew")
	(generator_version "10.0")
	(general
		(thickness 1.6)
		(legacy_teardrops no)
	)
	(paper "A4")
	(title_block
		(title "Bryce Canyon_R.DPB_16317-1_OCP.brd")
		(comment 1 "Bryce Canyon / footprints 1162-1164 of 2099")
	)
	(layers
		(0 "F.Cu" signal "TOP")
		(4 "In1.Cu" signal "L2GND")
		(6 "In2.Cu" signal "L3")
		(8 "In3.Cu" signal "L4VCC")
		(10 "In4.Cu" signal "L5VCC")
		(12 "In5.Cu" signal "L6")
		(14 "In6.Cu" signal "L7GND")
		(2 "B.Cu" signal "BOTTOM")
		(9 "F.Adhes" user "F.Adhesive")
		(11 "B.Adhes" user "B.Adhesive")
		(13 "F.Paste" user "Package Geometry/Pastemask Top")
		(15 "B.Paste" user "Package Geometry/Pastemask Bottom")
		(5 "F.SilkS" user "Ref Des/Silkscreen Top")
		(7 "B.SilkS" user "Ref Des/Silkscreen Bottom")
		(1 "F.Mask" user "Board Geometry/Soldermask Top")
		(3 "B.Mask" user "Board Geometry/Soldermask Bottom")
		(17 "Dwgs.User" user "User.Drawings")
		(19 "Cmts.User" user "User.Comments")
		(21 "Eco1.User" user "User.Eco1")
		(23 "Eco2.User" user "User.Eco2")
		(25 "Edge.Cuts" user "Board Geometry/Outline")
		(27 "Margin" user)
		(31 "F.CrtYd" user "Package Geometry/Place Bound Top")
		(29 "B.CrtYd" user "Package Geometry/Place Bound Bottom")
		(35 "F.Fab" user "Ref Des/Assembly Top")
		(33 "B.Fab" user "Ref Des/Assembly Bottom")
	)
	(footprint ""
		(layer "F.Cu")
		(at 325.550022 -143.91005 -90)
		(property "Reference" "HDDSAS18"
			(at 0 0 270)
			(layer "F.SilkS")
			(hide yes)
			(effects
				(font
					(size 1.27 1.27)
				)
			)
		)
		(property "Value" "SKT-SAS15P-14P-45-GP"
			(at -20.7645 -8.9789 270)
			(unlocked yes)
			(layer "F.Fab")
			(hide yes)
			(effects
				(font
					(size 1.016 1.016)
					(thickness 0.1524)
				)
			)
		)
		(property "Device Type" "10120818-001C-TRLF"
			(at -20.7645 -10.5029 270)
			(unlocked yes)
			(layer "F.Fab")
			(hide yes)
			(effects
				(font
					(size 1.016 1.016)
					(thickness 0.1524)
				)
			)
		)
		(duplicate_pad_numbers_are_jumpers no)
		(fp_line
			(start 1.651 4.2926)
			(end 1.651 3.0099)
			(stroke
				(width 0.1524)
				(type default)
			)
			(layer "F.SilkS")
		)
		(fp_line
			(start 8.509 4.2926)
			(end 1.651 4.2926)
			(stroke
				(width 0.1524)
				(type default)
			)
			(layer "F.SilkS")
		)
		(fp_line
			(start -23.4188 3.0099)
			(end -23.4188 -3.2512)
			(stroke
				(width 0.1524)
				(type default)
			)
			(layer "F.SilkS")
		)
		(fp_line
			(start 1.651 3.0099)
			(end -23.4188 3.0099)
			(stroke
				(width 0.1524)
				(type default)
			)
			(layer "F.SilkS")
		)
		(fp_line
			(start 8.509 3.0099)
			(end 8.509 4.2926)
			(stroke
				(width 0.1524)
				(type default)
			)
			(layer "F.SilkS")
		)
		(fp_line
			(start 23.4188 3.0099)
			(end 8.509 3.0099)
			(stroke
				(width 0.1524)
				(type default)
			)
			(layer "F.SilkS")
		)
		(fp_line
			(start -23.4188 -3.2512)
			(end 23.4188 -3.2512)
			(stroke
				(width 0.1524)
				(type default)
			)
			(layer "F.SilkS")
		)
		(fp_line
			(start 23.4188 -3.2512)
			(end 23.4188 3.0099)
			(stroke
				(width 0.1524)
				(type default)
			)
			(layer "F.SilkS")
		)
		(fp_line
			(start 15.5067 -3.3401)
			(end 16.2687 -3.3401)
			(stroke
				(width 0.3302)
				(type default)
			)
			(layer "F.SilkS")
		)
		(fp_poly
			(pts
				(xy 15.868904 -3.230372) (xy 16.503904 -3.865372) (xy 15.233904 -3.865372)
			)
			(stroke
				(width 0)
				(type default)
			)
			(fill yes)
			(layer "F.SilkS")
		)
		(fp_poly
			(pts
				(xy -22.8727 -2.7559) (xy 22.8727 -2.7559) (xy 22.8727 2.7559) (xy 8.255 2.7559) (xy 8.255 3.5179)
				(xy 1.905 3.5179) (xy 1.905 2.7559) (xy -22.8727 2.7559)
			)
			(stroke
				(width 0)
				(type default)
			)
			(fill no)
			(layer "F.CrtYd")
		)
		(fp_poly
			(pts
				(xy 1.397 4.5466) (xy 1.397 3.2639) (xy -23.6728 3.2639) (xy -23.6728 -3.5052) (xy 23.6728 -3.5052)
				(xy 23.6728 -0.00635) (xy 22.8727 -0.00635) (xy 22.8727 -2.7559) (xy -22.8727 -2.7559) (xy -22.8727 2.7559)
				(xy 1.905 2.7559) (xy 1.905 3.5179) (xy 8.255 3.5179) (xy 8.255 2.7559) (xy 22.8727 2.7559) (xy 22.8727 0.00635)
				(xy 23.6728 0.00635) (xy 23.6728 3.2639) (xy 8.763 3.2639) (xy 8.763 4.5466)
			)
			(stroke
				(width 0)
				(type default)
			)
			(fill no)
			(layer "F.CrtYd")
		)
		(fp_poly
			(pts
				(xy 1.397 4.5466) (xy 1.397 3.2639) (xy -23.6728 3.2639) (xy -23.6728 -3.5052) (xy 23.6728 -3.5052)
				(xy 23.6728 3.2639) (xy 8.763 3.2639) (xy 8.763 4.5466)
			)
			(stroke
				(width 0)
				(type default)
			)
			(fill no)
			(layer "F.Fab")
		)
		(pad "" np_thru_hole circle
			(at -18.874994 0 270)
			(size 0.254 0.254)
			(drill 1.3462)
			(layers "*.Cu" "*.Mask")
			(clearance 0.9017)
			(thermal_gap 0.9017)
		)
		(pad "" np_thru_hole circle
			(at 18.874994 0 270)
			(size 0.254 0.254)
			(drill 0.9398)
			(layers "*.Cu" "*.Mask")
			(clearance 0.6985)
			(thermal_gap 0.6985)
		)
		(pad "G1" smd rect
			(at 21.874988 0 270)
			(size 2.5908 2.5908)
			(layers "F.Cu" "F.Mask" "F.Paste")
			(net "GND")
		)
		(pad "G2" smd rect
			(at -21.874988 0 270)
			(size 2.5908 2.5908)
			(layers "F.Cu" "F.Mask" "F.Paste")
			(net "GND")
		)
		(pad "P1" smd rect
			(at 1.905 -1.82499 270)
			(size 0.6096 2.3622)
			(layers "F.Cu" "F.Mask" "F.Paste")
			(net "Net_1714")
		)
		(pad "P2" smd rect
			(at 0.635 -1.82499 270)
			(size 0.6096 2.3622)
			(layers "F.Cu" "F.Mask" "F.Paste")
			(net "Net_1715")
		)
		(pad "P3" smd rect
			(at -0.635 -1.82499 270)
			(size 0.6096 2.3622)
			(layers "F.Cu" "F.Mask" "F.Paste")
			(net "Net_1716")
		)
		(pad "P4" smd rect
			(at -1.905 -1.82499 270)
			(size 0.6096 2.3622)
			(layers "F.Cu" "F.Mask" "F.Paste")
			(net "GND")
		)
		(pad "P5" smd rect
			(at -3.175 -1.82499 270)
			(size 0.6096 2.3622)
			(layers "F.Cu" "F.Mask" "F.Paste")
			(net "HDD_PRSNT_18")
		)
		(pad "P6" smd rect
			(at -4.445 -1.82499 270)
			(size 0.6096 2.3622)
			(layers "F.Cu" "F.Mask" "F.Paste")
			(net "GND")
		)
		(pad "P7" smd rect
			(at -5.715 -1.82499 270)
			(size 0.6096 2.3622)
			(layers "F.Cu" "F.Mask" "F.Paste")
			(net "5V_PRE_18")
		)
		(pad "P8" smd rect
			(at -6.985 -1.82499 270)
			(size 0.6096 2.3622)
			(layers "F.Cu" "F.Mask" "F.Paste")
			(net "P5V_HDD18")
		)
		(pad "P9" smd rect
			(at -8.255 -1.82499 270)
			(size 0.6096 2.3622)
			(layers "F.Cu" "F.Mask" "F.Paste")
			(net "P5V_HDD18")
		)
		(pad "P10" smd rect
			(at -9.525 -1.82499 270)
			(size 0.6096 2.3622)
			(layers "F.Cu" "F.Mask" "F.Paste")
			(net "GND")
		)
		(pad "P11" smd rect
			(at -10.795 -1.82499 270)
			(size 0.6096 2.3622)
			(layers "F.Cu" "F.Mask" "F.Paste")
			(net "ACT_HDD_18")
		)
		(pad "P12" smd rect
			(at -12.065 -1.82499 270)
			(size 0.6096 2.3622)
			(layers "F.Cu" "F.Mask" "F.Paste")
			(net "GND")
		)
		(pad "P13" smd rect
			(at -13.335 -1.82499 270)
			(size 0.6096 2.3622)
			(layers "F.Cu" "F.Mask" "F.Paste")
			(net "12V_PRE_18")
		)
		(pad "P14" smd rect
			(at -14.605 -1.82499 270)
			(size 0.6096 2.3622)
			(layers "F.Cu" "F.Mask" "F.Paste")
			(net "P12V_HDD18")
		)
		(pad "P15" smd rect
			(at -15.875 -1.82499 270)
			(size 0.6096 2.3622)
			(layers "F.Cu" "F.Mask" "F.Paste")
			(net "P12V_HDD18")
		)
		(pad "S1" smd rect
			(at 15.875 -1.82499 270)
			(size 0.6096 2.3622)
			(layers "F.Cu" "F.Mask" "F.Paste")
			(net "GND")
		)
		(pad "S2" smd rect
			(at 14.605 -1.82499 270)
			(size 0.6096 2.3622)
			(layers "F.Cu" "F.Mask" "F.Paste")
			(net "SAS_HDD_RX_P18")
		)
		(pad "S3" smd rect
			(at 13.335 -1.82499 270)
			(size 0.6096 2.3622)
			(layers "F.Cu" "F.Mask" "F.Paste")
			(net "SAS_HDD_RX_N18")
		)
		(pad "S4" smd rect
			(at 12.065 -1.82499 270)
			(size 0.6096 2.3622)
			(layers "F.Cu" "F.Mask" "F.Paste")
			(net "GND")
		)
		(pad "S5" smd rect
			(at 10.795 -1.82499 270)
			(size 0.6096 2.3622)
			(layers "F.Cu" "F.Mask" "F.Paste")
			(net "PHY_DRV_B_TO_SCC_B_18_DN")
		)
		(pad "S6" smd rect
			(at 9.525 -1.82499 270)
			(size 0.6096 2.3622)
			(layers "F.Cu" "F.Mask" "F.Paste")
			(net "PHY_DRV_B_TO_SCC_B_18_DP")
		)
		(pad "S7" smd rect
			(at 8.255 -1.82499 270)
			(size 0.6096 2.3622)
			(layers "F.Cu" "F.Mask" "F.Paste")
			(net "GND")
		)
		(pad "S8" smd rect
			(at 7.480046 2.845054 270)
			(size 0.508 2.3622)
			(layers "F.Cu" "F.Mask" "F.Paste")
			(net "GND")
		)
		(pad "S9" smd rect
			(at 6.679946 2.845054 270)
			(size 0.508 2.3622)
			(layers "F.Cu" "F.Mask" "F.Paste")
			(net "Net_441")
		)
		(pad "S10" smd rect
			(at 5.8801 2.845054 270)
			(size 0.508 2.3622)
			(layers "F.Cu" "F.Mask" "F.Paste")
			(net "Net_333")
		)
		(pad "S11" smd rect
			(at 5.08 2.845054 270)
			(size 0.508 2.3622)
			(layers "F.Cu" "F.Mask" "F.Paste")
			(net "GND")
		)
		(pad "S12" smd rect
			(at 4.2799 2.845054 270)
			(size 0.508 2.3622)
			(layers "F.Cu" "F.Mask" "F.Paste")
			(net "Net_369")
		)
		(pad "S13" smd rect
			(at 3.480054 2.845054 270)
			(size 0.508 2.3622)
			(layers "F.Cu" "F.Mask" "F.Paste")
			(net "Net_405")
		)
		(pad "S14" smd rect
			(at 2.679954 2.845054 270)
			(size 0.508 2.3622)
			(layers "F.Cu" "F.Mask" "F.Paste")
			(net "GND")
		)
		(zone
			(layer "F.Cu")
			(hatch none 0.5)
			(connect_pads
				(clearance 0)
			)
			(min_thickness 0.25)
			(keepout
				(tracks allowed)
				(vias not_allowed)
				(pads allowed)
				(copperpour not_allowed)
				(footprints allowed)
			)
			(placement
				(enabled no)
				(sheetname "")
			)
			(fill
				(thermal_gap 0.5)
				(thermal_bridge_width 0.5)
				(island_removal_mode 0)
			)
			(polygon
				(pts
					(xy 329.207622 -160.64865) (xy 322.133722 -160.64865) (xy 322.133722 -167.58285) (xy 323.238622 -167.58285)
					(xy 323.238622 -163.46805) (xy 327.861422 -163.46805) (xy 327.861422 -167.58285) (xy 329.207622 -167.58285)
				)
			)
		)
		(zone
			(layer "F.Cu")
			(hatch none 0.5)
			(connect_pads
				(clearance 0)
			)
			(min_thickness 0.25)
			(keepout
				(tracks not_allowed)
				(vias allowed)
				(pads allowed)
				(copperpour not_allowed)
				(footprints allowed)
			)
			(placement
				(enabled no)
				(sheetname "")
			)
			(fill
				(thermal_gap 0.5)
				(thermal_bridge_width 0.5)
				(island_removal_mode 0)
			)
			(polygon
				(pts
					(xy 329.207622 -160.64865) (xy 322.133722 -160.64865) (xy 322.133722 -167.58285) (xy 323.238622 -167.58285)
					(xy 323.238622 -163.46805) (xy 327.861422 -163.46805) (xy 327.861422 -167.58285) (xy 329.207622 -167.58285)
				)
			)
		)
		(zone
			(layer "F.Cu")
			(hatch none 0.5)
			(connect_pads
				(clearance 0)
			)
			(min_thickness 0.25)
			(keepout
				(tracks allowed)
				(vias not_allowed)
				(pads allowed)
				(copperpour not_allowed)
				(footprints allowed)
			)
			(placement
				(enabled no)
				(sheetname "")
			)
			(fill
				(thermal_gap 0.5)
				(thermal_bridge_width 0.5)
				(island_removal_mode 0)
			)
			(polygon
				(pts
					(xy 329.207622 -127.17145) (xy 322.133722 -127.17145) (xy 322.133722 -120.23725) (xy 323.238622 -120.23725)
					(xy 323.238622 -124.35205) (xy 327.861422 -124.35205) (xy 327.861422 -120.23725) (xy 329.207622 -120.23725)
				)
			)
		)
		(zone
			(layer "F.Cu")
			(hatch none 0.5)
			(connect_pads
				(clearance 0)
			)
			(min_thickness 0.25)
			(keepout
				(tracks not_allowed)
				(vias allowed)
				(pads allowed)
				(copperpour not_allowed)
				(footprints allowed)
			)
			(placement
				(enabled no)
				(sheetname "")
			)
			(fill
				(thermal_gap 0.5)
				(thermal_bridge_width 0.5)
				(island_removal_mode 0)
			)
			(polygon
				(pts
					(xy 329.207622 -127.17145) (xy 322.133722 -127.17145) (xy 322.133722 -120.23725) (xy 323.238622 -120.23725)
					(xy 323.238622 -124.35205) (xy 327.861422 -124.35205) (xy 327.861422 -120.23725) (xy 329.207622 -120.23725)
				)
			)
		)
		(zone
			(layers "F.Cu" "B.Cu" "In1.Cu" "In2.Cu" "In3.Cu" "In4.Cu" "In5.Cu" "In6.Cu")
			(hatch none 0.5)
			(connect_pads
				(clearance 0)
			)
			(min_thickness 0.25)
			(keepout
				(tracks not_allowed)
				(vias allowed)
				(pads allowed)
				(copperpour not_allowed)
				(footprints allowed)
			)
			(placement
				(enabled no)
				(sheetname "")
			)
			(fill
				(thermal_gap 0.5)
				(thermal_bridge_width 0.5)
				(island_removal_mode 0)
			)
			(polygon
				(pts
					(arc
						(start 326.324722 -125.035056)
						(mid 324.775322 -125.035056)
						(end 326.324722 -125.035056)
					)
				)
			)
		)
		(zone
			(layers "F.Cu" "B.Cu" "In1.Cu" "In2.Cu" "In3.Cu" "In4.Cu" "In5.Cu" "In6.Cu")
			(hatch none 0.5)
			(connect_pads
				(clearance 0)
			)
			(min_thickness 0.25)
			(keepout
				(tracks not_allowed)
				(vias allowed)
				(pads allowed)
				(copperpour not_allowed)
				(footprints allowed)
			)
			(placement
				(enabled no)
				(sheetname "")
			)
			(fill
				(thermal_gap 0.5)
				(thermal_bridge_width 0.5)
				(island_removal_mode 0)
			)
			(polygon
				(pts
					(arc
						(start 326.527922 -162.785044)
						(mid 324.572122 -162.785044)
						(end 326.527922 -162.785044)
					)
				)
			)
		)
	)
	(footprint ""
		(layer "F.Cu")
		(at 190.213488 -244.660674 90)
		(property "Reference" "C93"
			(at 0 0 90)
			(layer "F.SilkS")
			(hide yes)
			(effects
				(font
					(size 1.27 1.27)
				)
			)
		)
		(property "Value" "SCD01U16V1KX-GP"
			(at -2.8321 -1.7399 90)
			(unlocked yes)
			(layer "F.Fab")
			(hide yes)
			(effects
				(font
					(size 1.016 1.016)
					(thickness 0.1524)
				)
			)
		)
		(property "Device Type" "C0201H13"
			(at -2.8321 -3.2639 90)
			(unlocked yes)
			(layer "F.Fab")
			(hide yes)
			(effects
				(font
					(size 1.016 1.016)
					(thickness 0.1524)
				)
			)
		)
		(duplicate_pad_numbers_are_jumpers no)
		(fp_rect
			(start -0.2794 0.6477)
			(end 0.2794 -0.6477)
			(stroke
				(width 0)
				(type default)
			)
			(fill no)
			(layer "F.CrtYd")
		)
		(fp_rect
			(start -0.2794 0.6477)
			(end 0.2794 -0.6477)
			(stroke
				(width 0)
				(type default)
			)
			(fill no)
			(layer "F.Fab")
		)
		(pad "1" smd custom
			(at 0 -0.2794 90)
			(size 0.0762 0.0762)
			(layers "F.Cu" "F.Mask" "F.Paste")
			(net "SAS_HDD_RX_P5")
			(options
				(clearance outline)
				(anchor circle)
			)
			(primitives
				(gr_poly
					(pts
						(arc
							(start 0.1524 -0.127)
							(mid 0.137521 -0.162921)
							(end 0.1016 -0.1778)
						)
						(arc
							(start -0.1016 -0.1778)
							(mid -0.137521 -0.162921)
							(end -0.1524 -0.127)
						)
						(arc
							(start -0.1524 0.127)
							(mid -0.137521 0.162921)
							(end -0.1016 0.1778)
						)
						(arc
							(start 0.1016 0.1778)
							(mid 0.137521 0.162921)
							(end 0.1524 0.127)
						)
					)
					(width 0)
					(fill yes)
				)
			)
		)
		(pad "2" smd custom
			(at 0 0.2794 90)
			(size 0.0762 0.0762)
			(layers "F.Cu" "F.Mask" "F.Paste")
			(net "PHY_SCC_B_TO_DRV_B_5_DP")
			(options
				(clearance outline)
				(anchor circle)
			)
			(primitives
				(gr_poly
					(pts
						(arc
							(start 0.1524 -0.127)
							(mid 0.137521 -0.162921)
							(end 0.1016 -0.1778)
						)
						(arc
							(start -0.1016 -0.1778)
							(mid -0.137521 -0.162921)
							(end -0.1524 -0.127)
						)
						(arc
							(start -0.1524 0.127)
							(mid -0.137521 0.162921)
							(end -0.1016 0.1778)
						)
						(arc
							(start 0.1016 0.1778)
							(mid 0.137521 0.162921)
							(end 0.1524 0.127)
						)
					)
					(width 0)
					(fill yes)
				)
			)
		)
	)
	(footprint ""
		(layer "F.Cu")
		(at 109.474 -140.462 90)
		(property "Reference" "C234"
			(at 0 0 90)
			(layer "F.SilkS")
			(hide yes)
			(effects
				(font
					(size 1.27 1.27)
				)
			)
		)
		(property "Value" "SCD033U25V2KX-GP"
			(at 1.1811 -2.7051 90)
			(unlocked yes)
			(layer "F.Fab")
			(hide yes)
			(effects
				(font
					(size 1.016 1.016)
					(thickness 0.1524)
				)
			)
		)
		(property "Device Type" "C402H22"
			(at 1.1811 -4.2291 90)
			(unlocked yes)
			(layer "F.Fab")
			(hide yes)
			(effects
				(font
					(size 1.016 1.016)
					(thickness 0.1524)
				)
			)
		)
		(duplicate_pad_numbers_are_jumpers no)
		(fp_rect
			(start -0.4318 0.9525)
			(end 0.4318 -0.9525)
			(stroke
				(width 0)
				(type default)
			)
			(fill no)
			(layer "F.CrtYd")
		)
		(fp_rect
			(start -0.4318 0.9525)
			(end 0.4318 -0.9525)
			(stroke
				(width 0)
				(type default)
			)
			(fill no)
			(layer "F.Fab")
		)
		(pad "1" smd custom
			(at 0 -0.4445 90)
			(size 0.1524 0.1524)
			(layers "F.Cu" "F.Mask" "F.Paste")
			(net "P12V_B")
			(options
				(clearance outline)
				(anchor circle)
			)
			(primitives
				(gr_poly
					(pts
						(arc
							(start 0.3048 -0.2032)
							(mid 0.275042 -0.275042)
							(end 0.2032 -0.3048)
						)
						(arc
							(start -0.2032 -0.3048)
							(mid -0.275042 -0.275042)
							(end -0.3048 -0.2032)
						)
						(arc
							(start -0.3048 0.2032)
							(mid -0.275042 0.275042)
							(end -0.2032 0.3048)
						)
						(arc
							(start 0.2032 0.3048)
							(mid 0.275042 0.275042)
							(end 0.3048 0.2032)
						)
					)
					(width 0)
					(fill yes)
				)
			)
		)
		(pad "2" smd custom
			(at 0 0.4445 90)
			(size 0.1524 0.1524)
			(layers "F.Cu" "F.Mask" "F.Paste")
			(net "SW_HDD_N15")
			(options
				(clearance outline)
				(anchor circle)
			)
			(primitives
				(gr_poly
					(pts
						(arc
							(start 0.3048 -0.2032)
							(mid 0.275042 -0.275042)
							(end 0.2032 -0.3048)
						)
						(arc
							(start -0.2032 -0.3048)
							(mid -0.275042 -0.275042)
							(end -0.3048 -0.2032)
						)
						(arc
							(start -0.3048 0.2032)
							(mid -0.275042 0.275042)
							(end -0.2032 0.3048)
						)
						(arc
							(start 0.2032 0.3048)
							(mid 0.275042 0.275042)
							(end 0.3048 0.2032)
						)
					)
					(width 0)
					(fill yes)
				)
			)
		)
	)
)
